FILE_TYPE=LIBRARY_PARTS;
primitive 'CONN8_TSW10407FD';
  pin
    '5':
      PIN_NUMBER='(5)';
      BIDIRECTIONAL='TRUE';
      INPUT_LOAD='(-0.01,0.01)';
      OUTPUT_LOAD='(1.0,-1.0)';
    '6':
      PIN_NUMBER='(6)';
      BIDIRECTIONAL='TRUE';
      INPUT_LOAD='(-0.01,0.01)';
      OUTPUT_LOAD='(1.0,-1.0)';
    '7':
      PIN_NUMBER='(7)';
      BIDIRECTIONAL='TRUE';
      INPUT_LOAD='(-0.01,0.01)';
      OUTPUT_LOAD='(1.0,-1.0)';
    '8':
      PIN_NUMBER='(8)';
      BIDIRECTIONAL='TRUE';
      INPUT_LOAD='(-0.01,0.01)';
      OUTPUT_LOAD='(1.0,-1.0)';
    '3':
      PIN_NUMBER='(3)';
      BIDIRECTIONAL='TRUE';
      INPUT_LOAD='(-0.01,0.01)';
      OUTPUT_LOAD='(1.0,-1.0)';
    '1':
      PIN_NUMBER='(1)';
      BIDIRECTIONAL='TRUE';
      INPUT_LOAD='(-0.01,0.01)';
      OUTPUT_LOAD='(1.0,-1.0)';
    '4':
      PIN_NUMBER='(4)';
      BIDIRECTIONAL='TRUE';
      INPUT_LOAD='(-0.01,0.01)';
      OUTPUT_LOAD='(1.0,-1.0)';
    '2':
      PIN_NUMBER='(2)';
      BIDIRECTIONAL='TRUE';
      INPUT_LOAD='(-0.01,0.01)';
      OUTPUT_LOAD='(1.0,-1.0)';
  end_pin;
  body
    PART_NAME='CONN8_TSW10407FD';
    BODY_NAME='CONN8_TSW10407FD';
    PHYS_DES_PREFIX='J';
    CLASS='IO';
  end_body;
end_primitive;

END.
